FILE_TYPE = MULTI_PHYS_TABLE;

PART 'NB695GDZ'

{========================================================================================}
:VALUE       | PART_TYPE | MATERIAL | PART_NUMBER    = STANDARD    | LIFECYCLE     | PART_NUMBER   | JEDEC_TYPE  | DESCRIPTION                     | MANUFTR | MANUF_PN    | RD_CMPLS_LVL | CMPLS_LVL | FROM_PJ    | CLASS | DIP_SMD | DATA                | EE_CHECK_LIST | FP_ECN | PSL | CREATOR | STATUS | MSD  | ESD_CDM | ESD_HBM | ESD_MM | PIN_LENGTH_SHORT_PIN | PIN_LENGTH_LONG_PIN | CREATEDAY  ;
{========================================================================================}
 'NB695GD-Z' | 'SMLF'    | 'IC'     | 'AL000695001'(!) = ''               | ''               | 'AL000695001' |'QFN13_2X3'| 'IC CTRL(13P)NB695GD-Z(QFN-13)' | 'MPS'   | 'NB695GD-Z' | 'EP(V1)'     | 'EP(V1)'  | 'S6L-MARK' | 'IC'  | ''      | 'MPS_NB695GD-Z.pdf' | ''            | ''     | ''  | ''      | ''     | 'NA' | 'N/A'   | 'N/A'   | 'N/A'  | '0 MILS'             | '0 MILS'            | '20190314'
 'NB695GD-Z' | 'SMLF'    | 'EMPTY'  | 'AL000695001'(!) = ''               | ''               | 'AL000695001' |'QFN13_2X3'| 'IC CTRL(13P)NB695GD-Z(QFN-13)' | 'MPS'   | 'NB695GD-Z' | 'EP(V1)'     | 'EP(V1)'  | 'S6L-MARK' | 'IC'  | ''      | 'MPS_NB695GD-Z.pdf' | ''            | ''     | ''  | ''      | ''     | 'NA' | 'N/A'   | 'N/A'   | 'N/A'  | '0 MILS'             | '0 MILS'            | '20190314'

END_PART

END.

